# T6G (Grand Teton) — schematic netlist excerpt (pin names and nets, part order shuffled) for the footprints in the layout excerpt that follows; sources: Cadence DE-HDL packaged netlist, KiCad conversion of 04192023_DAF0TMB3IC0_F0TG_MB_C_brd_V02_OCP.brd

C1834  Q_CAP  0.1UF 25V 10% X7R  pkg 0402  page 137 : A = P12V_OCP_V3_2_R ; B = GND
C478  Q_CAP  22UF 4V 20% X6S  pkg C0402  page 356 : A = P0V9_CPU1_RT_2D ; B = GND

(kicad_pcb
	(version 20260206)
	(generator "pcbnew")
	(generator_version "10.0")
	(general
		(thickness 1.6)
		(legacy_teardrops no)
	)
	(paper "A4")
	(title_block
		(title "04192023_DAF0TMB3IC0_F0TG_MB_C_brd_V02_OCP.brd")
		(comment 1 "Grand Teton / footprints 7350-7351 of 8354")
	)
	(layers
		(0 "F.Cu" signal "TOP")
		(4 "In1.Cu" signal "GND")
		(6 "In2.Cu" signal "IN1")
		(8 "In3.Cu" signal "GND1")
		(10 "In4.Cu" signal "IN2")
		(12 "In5.Cu" signal "GND2")
		(14 "In6.Cu" signal "IN3")
		(16 "In7.Cu" signal "GND3")
		(18 "In8.Cu" signal "VCC")
		(20 "In9.Cu" signal "VCC1")
		(22 "In10.Cu" signal "GND4")
		(24 "In11.Cu" signal "IN4")
		(26 "In12.Cu" signal "GND5")
		(28 "In13.Cu" signal "IN5")
		(30 "In14.Cu" signal "GND6")
		(32 "In15.Cu" signal "IN6")
		(34 "In16.Cu" signal "GND7")
		(2 "B.Cu" signal "BOTTOM")
		(9 "F.Adhes" user "F.Adhesive")
		(11 "B.Adhes" user "B.Adhesive")
		(13 "F.Paste" user "Package Geometry/Pastemask Top")
		(15 "B.Paste" user "Package Geometry/Pastemask Bottom")
		(5 "F.SilkS" user "Ref Des/Silkscreen Top")
		(7 "B.SilkS" user "Ref Des/Silkscreen Bottom")
		(1 "F.Mask" user "Board Geometry/Soldermask Top")
		(3 "B.Mask" user "Board Geometry/Soldermask Bottom")
		(17 "Dwgs.User" user "User.Drawings")
		(19 "Cmts.User" user "User.Comments")
		(21 "Eco1.User" user "User.Eco1")
		(23 "Eco2.User" user "User.Eco2")
		(25 "Edge.Cuts" user "Board Geometry/Outline")
		(27 "Margin" user)
		(31 "F.CrtYd" user "Package Geometry/Place Bound Top")
		(29 "B.CrtYd" user "Package Geometry/Place Bound Bottom")
		(35 "F.Fab" user "Ref Des/Assembly Top")
		(33 "B.Fab" user "Ref Des/Assembly Bottom")
	)
	(footprint ""
		(layer "B.Cu")
		(at 125.291342 -390.560052 90)
		(property "Reference" "C478"
			(at 0 0 90)
			(layer "B.SilkS")
			(hide yes)
			(effects
				(font
					(size 1.27 1.27)
				)
				(justify mirror)
			)
		)
		(property "Value" ""
			(at 0 0 90)
			(layer "B.Fab")
			(effects
				(font
					(size 1.27 1.27)
				)
				(justify mirror)
			)
		)
		(duplicate_pad_numbers_are_jumpers no)
		(fp_line
			(start 0.7874 -0.4064)
			(end -0.7874 -0.4064)
			(stroke
				(width 0.1524)
				(type default)
			)
			(layer "B.SilkS")
		)
		(fp_line
			(start -0.7874 -0.4064)
			(end -0.7874 0.4064)
			(stroke
				(width 0.1524)
				(type default)
			)
			(layer "B.SilkS")
		)
		(fp_line
			(start 0.7874 0.4064)
			(end 0.7874 -0.4064)
			(stroke
				(width 0.1524)
				(type default)
			)
			(layer "B.SilkS")
		)
		(fp_line
			(start -0.7874 0.4064)
			(end 0.7874 0.4064)
			(stroke
				(width 0.1524)
				(type default)
			)
			(layer "B.SilkS")
		)
		(fp_line
			(start 0.67945 -0.305054)
			(end 0.12065 -0.305054)
			(stroke
				(width 0.1)
				(type default)
			)
			(layer "B.Fab")
		)
		(fp_line
			(start 0.12065 -0.305054)
			(end 0.12065 -0.2794)
			(stroke
				(width 0.1)
				(type default)
			)
			(layer "B.Fab")
		)
		(fp_line
			(start -0.12065 -0.3048)
			(end -0.67945 -0.3048)
			(stroke
				(width 0.1)
				(type default)
			)
			(layer "B.Fab")
		)
		(fp_line
			(start -0.67945 -0.3048)
			(end -0.67945 0.3048)
			(stroke
				(width 0.1)
				(type default)
			)
			(layer "B.Fab")
		)
		(fp_line
			(start 0.12065 -0.2794)
			(end -0.12065 -0.2794)
			(stroke
				(width 0.1)
				(type default)
			)
			(layer "B.Fab")
		)
		(fp_line
			(start -0.12065 -0.2794)
			(end -0.12065 -0.3048)
			(stroke
				(width 0.1)
				(type default)
			)
			(layer "B.Fab")
		)
		(fp_line
			(start 0.12065 0.2794)
			(end 0.12065 0.3048)
			(stroke
				(width 0.1)
				(type default)
			)
			(layer "B.Fab")
		)
		(fp_line
			(start -0.120396 0.2794)
			(end 0.12065 0.2794)
			(stroke
				(width 0.1)
				(type default)
			)
			(layer "B.Fab")
		)
		(fp_line
			(start 0.67945 0.3048)
			(end 0.67945 -0.305054)
			(stroke
				(width 0.1)
				(type default)
			)
			(layer "B.Fab")
		)
		(fp_line
			(start 0.12065 0.3048)
			(end 0.67945 0.3048)
			(stroke
				(width 0.1)
				(type default)
			)
			(layer "B.Fab")
		)
		(fp_line
			(start -0.120396 0.3048)
			(end -0.120396 0.2794)
			(stroke
				(width 0.1)
				(type default)
			)
			(layer "B.Fab")
		)
		(fp_line
			(start -0.67945 0.3048)
			(end -0.120396 0.3048)
			(stroke
				(width 0.1)
				(type default)
			)
			(layer "B.Fab")
		)
		(pad "1" smd circle
			(at 0.40005 0 270)
			(size 0 0)
			(layers "B.Cu" "B.Mask" "B.Paste")
			(net "P0V9_CPU1_RT_2D")
		)
		(pad "2" smd circle
			(at -0.40005 0 270)
			(size 0 0)
			(layers "B.Cu" "B.Mask" "B.Paste")
			(net "GND")
		)
	)
	(footprint ""
		(layer "B.Cu")
		(at 65.3796 -15.8496)
		(property "Reference" "C1834"
			(at 0 0 0)
			(layer "B.SilkS")
			(hide yes)
			(effects
				(font
					(size 1.27 1.27)
				)
				(justify mirror)
			)
		)
		(property "Value" ""
			(at 0 0 0)
			(layer "B.Fab")
			(effects
				(font
					(size 1.27 1.27)
				)
				(justify mirror)
			)
		)
		(duplicate_pad_numbers_are_jumpers no)
		(fp_line
			(start -0.7874 -0.4064)
			(end -0.7874 0.4064)
			(stroke
				(width 0.1524)
				(type default)
			)
			(layer "B.SilkS")
		)
		(fp_line
			(start -0.7874 0.4064)
			(end 0.7874 0.4064)
			(stroke
				(width 0.1524)
				(type default)
			)
			(layer "B.SilkS")
		)
		(fp_line
			(start 0.7874 -0.4064)
			(end -0.7874 -0.4064)
			(stroke
				(width 0.1524)
				(type default)
			)
			(layer "B.SilkS")
		)
		(fp_line
			(start 0.7874 0.4064)
			(end 0.7874 -0.4064)
			(stroke
				(width 0.1524)
				(type default)
			)
			(layer "B.SilkS")
		)
		(fp_line
			(start -0.67945 -0.3048)
			(end -0.67945 0.3048)
			(stroke
				(width 0.1)
				(type default)
			)
			(layer "B.Fab")
		)
		(fp_line
			(start -0.67945 0.3048)
			(end -0.120396 0.3048)
			(stroke
				(width 0.1)
				(type default)
			)
			(layer "B.Fab")
		)
		(fp_line
			(start -0.12065 -0.3048)
			(end -0.67945 -0.3048)
			(stroke
				(width 0.1)
				(type default)
			)
			(layer "B.Fab")
		)
		(fp_line
			(start -0.12065 -0.2794)
			(end -0.12065 -0.3048)
			(stroke
				(width 0.1)
				(type default)
			)
			(layer "B.Fab")
		)
		(fp_line
			(start -0.120396 0.2794)
			(end 0.12065 0.2794)
			(stroke
				(width 0.1)
				(type default)
			)
			(layer "B.Fab")
		)
		(fp_line
			(start -0.120396 0.3048)
			(end -0.120396 0.2794)
			(stroke
				(width 0.1)
				(type default)
			)
			(layer "B.Fab")
		)
		(fp_line
			(start 0.12065 -0.305054)
			(end 0.12065 -0.2794)
			(stroke
				(width 0.1)
				(type default)
			)
			(layer "B.Fab")
		)
		(fp_line
			(start 0.12065 -0.2794)
			(end -0.12065 -0.2794)
			(stroke
				(width 0.1)
				(type default)
			)
			(layer "B.Fab")
		)
		(fp_line
			(start 0.12065 0.2794)
			(end 0.12065 0.3048)
			(stroke
				(width 0.1)
				(type default)
			)
			(layer "B.Fab")
		)
		(fp_line
			(start 0.12065 0.3048)
			(end 0.67945 0.3048)
			(stroke
				(width 0.1)
				(type default)
			)
			(layer "B.Fab")
		)
		(fp_line
			(start 0.67945 -0.305054)
			(end 0.12065 -0.305054)
			(stroke
				(width 0.1)
				(type default)
			)
			(layer "B.Fab")
		)
		(fp_line
			(start 0.67945 0.3048)
			(end 0.67945 -0.305054)
			(stroke
				(width 0.1)
				(type default)
			)
			(layer "B.Fab")
		)
		(pad "1" smd circle
			(at 0.40005 0 180)
			(size 0 0)
			(layers "B.Cu" "B.Mask" "B.Paste")
			(net "P12V_OCP_V3_2_R")
		)
		(pad "2" smd circle
			(at -0.40005 0 180)
			(size 0 0)
			(layers "B.Cu" "B.Mask" "B.Paste")
			(net "GND")
		)
	)
)
